# S9S_MB_2U (Grand Teton) — schematic netlist excerpt (pin names and nets, part order shuffled) for the footprints in the layout excerpt that follows; sources: Cadence DE-HDL packaged netlist, KiCad conversion of 03242023_DA0F0TMBIJ0_F0T_Motherboard_J_brd_V01_OCP.brd

PR4250  Q_RES  499 1% CHIP  pkg 0402LF  page 294 : A = PVCCFA_EHV_CPU1 ; B = GND
R3024  Q_RES  240 1% EMPTY  pkg 0402LF  page 119 : A = GND ; B = PD_EXT_CLK_SEL_CPU1

(kicad_pcb
	(version 20260206)
	(generator "pcbnew")
	(generator_version "10.0")
	(general
		(thickness 1.6)
		(legacy_teardrops no)
	)
	(paper "A4")
	(title_block
		(title "03242023_DA0F0TMBIJ0_F0T_Motherboard_J_brd_V01_OCP.brd")
		(comment 1 "Grand Teton / footprints 4847-4848 of 6105")
	)
	(layers
		(0 "F.Cu" signal "TOP")
		(4 "In1.Cu" signal "GND")
		(6 "In2.Cu" signal "IN1")
		(8 "In3.Cu" signal "GND1")
		(10 "In4.Cu" signal "IN2")
		(12 "In5.Cu" signal "GND2")
		(14 "In6.Cu" signal "IN3")
		(16 "In7.Cu" signal "GND3")
		(18 "In8.Cu" signal "VCC")
		(20 "In9.Cu" signal "VCC1")
		(22 "In10.Cu" signal "GND4")
		(24 "In11.Cu" signal "IN4")
		(26 "In12.Cu" signal "GND5")
		(28 "In13.Cu" signal "IN5")
		(30 "In14.Cu" signal "GND6")
		(32 "In15.Cu" signal "IN6")
		(34 "In16.Cu" signal "GND7")
		(2 "B.Cu" signal "BOTTOM")
		(9 "F.Adhes" user "F.Adhesive")
		(11 "B.Adhes" user "B.Adhesive")
		(13 "F.Paste" user "Package Geometry/Pastemask Top")
		(15 "B.Paste" user "Package Geometry/Pastemask Bottom")
		(5 "F.SilkS" user "Ref Des/Silkscreen Top")
		(7 "B.SilkS" user "Ref Des/Silkscreen Bottom")
		(1 "F.Mask" user "Board Geometry/Soldermask Top")
		(3 "B.Mask" user "Board Geometry/Soldermask Bottom")
		(17 "Dwgs.User" user "User.Drawings")
		(19 "Cmts.User" user "User.Comments")
		(21 "Eco1.User" user "User.Eco1")
		(23 "Eco2.User" user "User.Eco2")
		(25 "Edge.Cuts" user "Board Geometry/Outline")
		(27 "Margin" user)
		(31 "F.CrtYd" user "Package Geometry/Place Bound Top")
		(29 "B.CrtYd" user "Package Geometry/Place Bound Bottom")
		(35 "F.Fab" user "Ref Des/Assembly Top")
		(33 "B.Fab" user "Ref Des/Assembly Bottom")
	)
	(footprint ""
		(layer "B.Cu")
		(at 96.241108 -190.705232 -90)
		(property "Reference" "R3024"
			(at 0 0 90)
			(layer "B.SilkS")
			(hide yes)
			(effects
				(font
					(size 1.27 1.27)
				)
				(justify mirror)
			)
		)
		(property "Value" ""
			(at 0 0 90)
			(layer "B.Fab")
			(effects
				(font
					(size 1.27 1.27)
				)
				(justify mirror)
			)
		)
		(duplicate_pad_numbers_are_jumpers no)
		(fp_line
			(start -0.7874 0.4064)
			(end 0.7874 0.4064)
			(stroke
				(width 0.1524)
				(type default)
			)
			(layer "B.SilkS")
		)
		(fp_line
			(start 0.7874 0.4064)
			(end 0.7874 -0.4064)
			(stroke
				(width 0.1524)
				(type default)
			)
			(layer "B.SilkS")
		)
		(fp_line
			(start -0.7874 -0.4064)
			(end -0.7874 0.4064)
			(stroke
				(width 0.1524)
				(type default)
			)
			(layer "B.SilkS")
		)
		(fp_line
			(start 0.7874 -0.4064)
			(end -0.7874 -0.4064)
			(stroke
				(width 0.1524)
				(type default)
			)
			(layer "B.SilkS")
		)
		(fp_line
			(start -0.67945 0.3048)
			(end -0.120396 0.3048)
			(stroke
				(width 0.1)
				(type default)
			)
			(layer "B.Fab")
		)
		(fp_line
			(start -0.120396 0.3048)
			(end -0.120396 0.2794)
			(stroke
				(width 0.1)
				(type default)
			)
			(layer "B.Fab")
		)
		(fp_line
			(start 0.12065 0.3048)
			(end 0.67945 0.3048)
			(stroke
				(width 0.1)
				(type default)
			)
			(layer "B.Fab")
		)
		(fp_line
			(start 0.67945 0.3048)
			(end 0.67945 -0.305054)
			(stroke
				(width 0.1)
				(type default)
			)
			(layer "B.Fab")
		)
		(fp_line
			(start -0.120396 0.2794)
			(end 0.12065 0.2794)
			(stroke
				(width 0.1)
				(type default)
			)
			(layer "B.Fab")
		)
		(fp_line
			(start 0.12065 0.2794)
			(end 0.12065 0.3048)
			(stroke
				(width 0.1)
				(type default)
			)
			(layer "B.Fab")
		)
		(fp_line
			(start -0.12065 -0.2794)
			(end -0.12065 -0.3048)
			(stroke
				(width 0.1)
				(type default)
			)
			(layer "B.Fab")
		)
		(fp_line
			(start 0.12065 -0.2794)
			(end -0.12065 -0.2794)
			(stroke
				(width 0.1)
				(type default)
			)
			(layer "B.Fab")
		)
		(fp_line
			(start -0.67945 -0.3048)
			(end -0.67945 0.3048)
			(stroke
				(width 0.1)
				(type default)
			)
			(layer "B.Fab")
		)
		(fp_line
			(start -0.12065 -0.3048)
			(end -0.67945 -0.3048)
			(stroke
				(width 0.1)
				(type default)
			)
			(layer "B.Fab")
		)
		(fp_line
			(start 0.12065 -0.305054)
			(end 0.12065 -0.2794)
			(stroke
				(width 0.1)
				(type default)
			)
			(layer "B.Fab")
		)
		(fp_line
			(start 0.67945 -0.305054)
			(end 0.12065 -0.305054)
			(stroke
				(width 0.1)
				(type default)
			)
			(layer "B.Fab")
		)
		(pad "1" smd circle
			(at 0.40005 0 90)
			(size 0 0)
			(layers "B.Cu" "B.Mask" "B.Paste")
			(net "GND")
		)
		(pad "2" smd circle
			(at -0.40005 0 90)
			(size 0 0)
			(layers "B.Cu" "B.Mask" "B.Paste")
			(net "PD_EXT_CLK_SEL_CPU1")
		)
	)
	(footprint ""
		(layer "B.Cu")
		(at 61.690758 -179.02555)
		(property "Reference" "PR4250"
			(at 0 0 0)
			(layer "B.SilkS")
			(hide yes)
			(effects
				(font
					(size 1.27 1.27)
				)
				(justify mirror)
			)
		)
		(property "Value" ""
			(at 0 0 0)
			(layer "B.Fab")
			(effects
				(font
					(size 1.27 1.27)
				)
				(justify mirror)
			)
		)
		(duplicate_pad_numbers_are_jumpers no)
		(fp_line
			(start -0.7874 -0.4064)
			(end -0.7874 0.4064)
			(stroke
				(width 0.1524)
				(type default)
			)
			(layer "B.SilkS")
		)
		(fp_line
			(start -0.7874 0.4064)
			(end 0.7874 0.4064)
			(stroke
				(width 0.1524)
				(type default)
			)
			(layer "B.SilkS")
		)
		(fp_line
			(start 0.7874 -0.4064)
			(end -0.7874 -0.4064)
			(stroke
				(width 0.1524)
				(type default)
			)
			(layer "B.SilkS")
		)
		(fp_line
			(start 0.7874 0.4064)
			(end 0.7874 -0.4064)
			(stroke
				(width 0.1524)
				(type default)
			)
			(layer "B.SilkS")
		)
		(fp_line
			(start -0.67945 -0.3048)
			(end -0.67945 0.3048)
			(stroke
				(width 0.1)
				(type default)
			)
			(layer "B.Fab")
		)
		(fp_line
			(start -0.67945 0.3048)
			(end -0.120396 0.3048)
			(stroke
				(width 0.1)
				(type default)
			)
			(layer "B.Fab")
		)
		(fp_line
			(start -0.12065 -0.3048)
			(end -0.67945 -0.3048)
			(stroke
				(width 0.1)
				(type default)
			)
			(layer "B.Fab")
		)
		(fp_line
			(start -0.12065 -0.2794)
			(end -0.12065 -0.3048)
			(stroke
				(width 0.1)
				(type default)
			)
			(layer "B.Fab")
		)
		(fp_line
			(start -0.120396 0.2794)
			(end 0.12065 0.2794)
			(stroke
				(width 0.1)
				(type default)
			)
			(layer "B.Fab")
		)
		(fp_line
			(start -0.120396 0.3048)
			(end -0.120396 0.2794)
			(stroke
				(width 0.1)
				(type default)
			)
			(layer "B.Fab")
		)
		(fp_line
			(start 0.12065 -0.305054)
			(end 0.12065 -0.2794)
			(stroke
				(width 0.1)
				(type default)
			)
			(layer "B.Fab")
		)
		(fp_line
			(start 0.12065 -0.2794)
			(end -0.12065 -0.2794)
			(stroke
				(width 0.1)
				(type default)
			)
			(layer "B.Fab")
		)
		(fp_line
			(start 0.12065 0.2794)
			(end 0.12065 0.3048)
			(stroke
				(width 0.1)
				(type default)
			)
			(layer "B.Fab")
		)
		(fp_line
			(start 0.12065 0.3048)
			(end 0.67945 0.3048)
			(stroke
				(width 0.1)
				(type default)
			)
			(layer "B.Fab")
		)
		(fp_line
			(start 0.67945 -0.305054)
			(end 0.12065 -0.305054)
			(stroke
				(width 0.1)
				(type default)
			)
			(layer "B.Fab")
		)
		(fp_line
			(start 0.67945 0.3048)
			(end 0.67945 -0.305054)
			(stroke
				(width 0.1)
				(type default)
			)
			(layer "B.Fab")
		)
		(pad "1" smd circle
			(at 0.40005 0 180)
			(size 0 0)
			(layers "B.Cu" "B.Mask" "B.Paste")
			(net "PVCCFA_EHV_CPU1")
		)
		(pad "2" smd circle
			(at -0.40005 0 180)
			(size 0 0)
			(layers "B.Cu" "B.Mask" "B.Paste")
			(net "GND")
		)
	)
)
